FILE_TYPE = CONNECTIVITY;
{Allegro Design Entry HDL 17.2-2016 S081 (4005846) 1/11/2022}
"PAGE_NUMBER" = 135;
0"NC";
END.
